#ISCELL
  mstr_misc dns *
  *
#ISCELL
  pure_quanta quanta_title_block_c *
  *
#CELL
  pure_quanta q_res *
  page126_i114
#ISCELL
  standard offpage *
  page126_i133
#ISCELL
  standard offpage *
  page126_i134
#CELL
  pure_quanta q_res *
  page126_i135
#CELL
  pure_quanta q_res *
  page126_i136
#ISCELL
  logical_power universal_power *
  page126_i137
#ISCELL
  standard offpage *
  page126_i138
#ISCELL
  standard offpage *
  page126_i139
#CELL
  pure_quanta q_res *
  page126_i140
#CELL
  pure_quanta q_res *
  page126_i141
#CELL
  pure_quanta q_res *
  page126_i22
#CELL
  pure_quanta q_res *
  page126_i23
#ISCELL
  logical_power universal_power *
  page126_i24
#CELL
  pure_quanta q_res *
  page126_i25
#ISCELL
  standard offpage *
  page126_i42
#ISCELL
  standard offpage *
  page126_i43
#ISCELL
  standard offpage *
  page126_i44
#ISCELL
  standard offpage *
  page126_i45
